# BASEBOARD_FAB2 (Tioga Pass) — schematic netlist excerpt (pin names and nets, part order shuffled) for the footprints in the layout excerpt that follows; sources: Cadence DE-HDL packaged netlist, KiCad conversion of Wiwynn_Tioga_Pass_MB.brd

C3M17  CAP  10UF 4V 20% X6S  pkg 0603LF  page 127 : A = P1V05_PCH_STBY_VCCA_PLL1 ; B = GND
C2L11  CAP_A  0.1UF 16V 10% X7R  pkg 0402V  page 235 : A = VR_PVNN_PCH_VDD ; B = GND
R7G26  RES  10.0K 1% CHIP  pkg 0402  page 136 : A = P3V3_STBY ; B = FM_ME_RECOVER_N

(kicad_pcb
	(version 20260206)
	(generator "pcbnew")
	(generator_version "10.0")
	(general
		(thickness 1.6)
		(legacy_teardrops no)
	)
	(paper "A4")
	(title_block
		(title "Wiwynn_Tioga_Pass_MB.brd")
		(comment 1 "Tioga Pass / footprints 3290-3292 of 4770")
	)
	(layers
		(0 "F.Cu" signal "TOP")
		(4 "In1.Cu" signal "L2GND")
		(6 "In2.Cu" signal "L3")
		(8 "In3.Cu" signal "L4GND")
		(10 "In4.Cu" signal "L5")
		(12 "In5.Cu" signal "L6GND")
		(14 "In6.Cu" signal "L7VCC")
		(16 "In7.Cu" signal "L8VCC")
		(18 "In8.Cu" signal "L9GND")
		(20 "In9.Cu" signal "L10")
		(22 "In10.Cu" signal "L11GND")
		(24 "In11.Cu" signal "L12")
		(26 "In12.Cu" signal "L13GND")
		(2 "B.Cu" signal "BOTTOM")
		(9 "F.Adhes" user "F.Adhesive")
		(11 "B.Adhes" user "B.Adhesive")
		(13 "F.Paste" user "Package Geometry/Pastemask Top")
		(15 "B.Paste" user "Package Geometry/Pastemask Bottom")
		(5 "F.SilkS" user "Ref Des/Silkscreen Top")
		(7 "B.SilkS" user "Ref Des/Silkscreen Bottom")
		(1 "F.Mask" user "Board Geometry/Soldermask Top")
		(3 "B.Mask" user "Board Geometry/Soldermask Bottom")
		(17 "Dwgs.User" user "User.Drawings")
		(19 "Cmts.User" user "User.Comments")
		(21 "Eco1.User" user "User.Eco1")
		(23 "Eco2.User" user "User.Eco2")
		(25 "Edge.Cuts" user "Board Geometry/Outline")
		(27 "Margin" user)
		(31 "F.CrtYd" user "Package Geometry/Place Bound Top")
		(29 "B.CrtYd" user "Package Geometry/Place Bound Bottom")
		(35 "F.Fab" user "Ref Des/Assembly Top")
		(33 "B.Fab" user "Ref Des/Assembly Bottom")
	)
	(footprint ""
		(layer "B.Cu")
		(at 371.983 -6.1595)
		(property "Reference" "R7G26"
			(at 0 0 0)
			(layer "B.SilkS")
			(hide yes)
			(effects
				(font
					(size 1.27 1.27)
				)
				(justify mirror)
			)
		)
		(property "Value" ""
			(at 0 0 0)
			(layer "B.Fab")
			(effects
				(font
					(size 1.27 1.27)
				)
				(justify mirror)
			)
		)
		(duplicate_pad_numbers_are_jumpers no)
		(fp_poly
			(pts
				(xy 0.2794 -0.1016) (xy -0.2794 -0.1016) (xy -0.2794 0.9906) (xy 0.2794 0.9906)
			)
			(stroke
				(width 0)
				(type default)
			)
			(fill no)
			(layer "B.CrtYd")
		)
		(fp_line
			(start -0.2794 -0.1016)
			(end 0.2794 -0.1016)
			(stroke
				(width 0.1)
				(type default)
			)
			(layer "B.Fab")
		)
		(fp_line
			(start -0.2794 0.9906)
			(end -0.2794 -0.1016)
			(stroke
				(width 0.1)
				(type default)
			)
			(layer "B.Fab")
		)
		(fp_line
			(start 0.2794 -0.1016)
			(end 0.2794 0.9906)
			(stroke
				(width 0.1)
				(type default)
			)
			(layer "B.Fab")
		)
		(fp_line
			(start 0.2794 0.9906)
			(end -0.2794 0.9906)
			(stroke
				(width 0.1)
				(type default)
			)
			(layer "B.Fab")
		)
		(pad "1" smd rect
			(at 0 0 180)
			(size 0.508 0.508)
			(layers "B.Cu" "B.Mask" "B.Paste")
			(net "P3V3_STBY")
		)
		(pad "2" smd rect
			(at 0 0.889 180)
			(size 0.508 0.508)
			(layers "B.Cu" "B.Mask" "B.Paste")
			(net "FM_ME_RECOVER_N")
		)
		(zone
			(layer "B.Cu")
			(hatch none 0.5)
			(connect_pads
				(clearance 0)
			)
			(min_thickness 0.25)
			(keepout
				(tracks allowed)
				(vias not_allowed)
				(pads allowed)
				(copperpour not_allowed)
				(footprints allowed)
			)
			(placement
				(enabled no)
				(sheetname "")
			)
			(fill
				(thermal_gap 0.5)
				(thermal_bridge_width 0.5)
				(island_removal_mode 0)
			)
			(polygon
				(pts
					(xy 372.237 -5.9055) (xy 371.729 -5.9055) (xy 371.729 -5.5245) (xy 372.237 -5.5245)
				)
			)
		)
		(zone
			(layer "B.Cu")
			(hatch none 0.5)
			(connect_pads
				(clearance 0)
			)
			(min_thickness 0.25)
			(keepout
				(tracks not_allowed)
				(vias allowed)
				(pads allowed)
				(copperpour not_allowed)
				(footprints allowed)
			)
			(placement
				(enabled no)
				(sheetname "")
			)
			(fill
				(thermal_gap 0.5)
				(thermal_bridge_width 0.5)
				(island_removal_mode 0)
			)
			(polygon
				(pts
					(xy 372.237 -5.5245) (xy 371.729 -5.5245) (xy 371.729 -5.9055) (xy 372.237 -5.9055)
				)
			)
		)
	)
	(footprint ""
		(layer "B.Cu")
		(at 393.286234 -151.84374 90)
		(property "Reference" "C2L11"
			(at 0 0 90)
			(layer "B.SilkS")
			(hide yes)
			(effects
				(font
					(size 1.27 1.27)
				)
				(justify mirror)
			)
		)
		(property "Value" ""
			(at 0 0 90)
			(layer "B.Fab")
			(effects
				(font
					(size 1.27 1.27)
				)
				(justify mirror)
			)
		)
		(duplicate_pad_numbers_are_jumpers no)
		(fp_poly
			(pts
				(xy -0.3048 -0.1016) (xy -0.3048 0.9906) (xy 0.3048 0.9906) (xy 0.3048 -0.1016)
			)
			(stroke
				(width 0)
				(type default)
			)
			(fill no)
			(layer "B.CrtYd")
		)
		(fp_line
			(start 0.3048 -0.1016)
			(end 0.3048 0.9906)
			(stroke
				(width 0.1)
				(type default)
			)
			(layer "B.Fab")
		)
		(fp_line
			(start -0.3048 -0.1016)
			(end 0.3048 -0.1016)
			(stroke
				(width 0.1)
				(type default)
			)
			(layer "B.Fab")
		)
		(fp_line
			(start 0.3048 0.9906)
			(end -0.3048 0.9906)
			(stroke
				(width 0.1)
				(type default)
			)
			(layer "B.Fab")
		)
		(fp_line
			(start -0.3048 0.9906)
			(end -0.3048 -0.1016)
			(stroke
				(width 0.1)
				(type default)
			)
			(layer "B.Fab")
		)
		(pad "1" smd rect
			(at 0 0 270)
			(size 0.508 0.508)
			(layers "B.Cu" "B.Mask" "B.Paste")
			(net "VR_PVNN_PCH_VDD")
		)
		(pad "2" smd rect
			(at 0 0.889 270)
			(size 0.508 0.508)
			(layers "B.Cu" "B.Mask" "B.Paste")
			(net "GND")
		)
		(zone
			(layer "B.Cu")
			(hatch none 0.5)
			(connect_pads
				(clearance 0)
			)
			(min_thickness 0.25)
			(keepout
				(tracks allowed)
				(vias not_allowed)
				(pads allowed)
				(copperpour not_allowed)
				(footprints allowed)
			)
			(placement
				(enabled no)
				(sheetname "")
			)
			(fill
				(thermal_gap 0.5)
				(thermal_bridge_width 0.5)
				(island_removal_mode 0)
			)
			(polygon
				(pts
					(xy 393.540234 -152.09774) (xy 393.540234 -151.58974) (xy 393.921234 -151.58974) (xy 393.921234 -152.09774)
				)
			)
		)
		(zone
			(layer "B.Cu")
			(hatch none 0.5)
			(connect_pads
				(clearance 0)
			)
			(min_thickness 0.25)
			(keepout
				(tracks not_allowed)
				(vias allowed)
				(pads allowed)
				(copperpour not_allowed)
				(footprints allowed)
			)
			(placement
				(enabled no)
				(sheetname "")
			)
			(fill
				(thermal_gap 0.5)
				(thermal_bridge_width 0.5)
				(island_removal_mode 0)
			)
			(polygon
				(pts
					(xy 393.921234 -152.09774) (xy 393.921234 -151.58974) (xy 393.540234 -151.58974) (xy 393.540234 -152.09774)
				)
			)
		)
	)
	(footprint ""
		(layer "B.Cu")
		(at 378.0028 -137.8458 -90)
		(property "Reference" "C3M17"
			(at 0 0 90)
			(layer "B.SilkS")
			(hide yes)
			(effects
				(font
					(size 1.27 1.27)
				)
				(justify mirror)
			)
		)
		(property "Value" ""
			(at 0 0 90)
			(layer "B.Fab")
			(effects
				(font
					(size 1.27 1.27)
				)
				(justify mirror)
			)
		)
		(duplicate_pad_numbers_are_jumpers no)
		(fp_poly
			(pts
				(xy 0.4953 -0.2032) (xy -0.4953 -0.2032) (xy -0.4953 1.6002) (xy 0.4953 1.6002)
			)
			(stroke
				(width 0)
				(type default)
			)
			(fill no)
			(layer "B.CrtYd")
		)
		(fp_line
			(start -0.4953 1.6002)
			(end 0.4953 1.6002)
			(stroke
				(width 0.1)
				(type default)
			)
			(layer "B.Fab")
		)
		(fp_line
			(start 0.4953 1.6002)
			(end 0.4953 -0.2032)
			(stroke
				(width 0.1)
				(type default)
			)
			(layer "B.Fab")
		)
		(fp_line
			(start -0.4953 -0.2032)
			(end -0.4953 1.6002)
			(stroke
				(width 0.1)
				(type default)
			)
			(layer "B.Fab")
		)
		(fp_line
			(start 0.4953 -0.2032)
			(end -0.4953 -0.2032)
			(stroke
				(width 0.1)
				(type default)
			)
			(layer "B.Fab")
		)
		(pad "1" smd rect
			(at 0 0 90)
			(size 0.762 0.889)
			(layers "B.Cu" "B.Mask" "B.Paste")
			(net "P1V05_PCH_STBY_VCCA_PLL1")
		)
		(pad "2" smd rect
			(at 0 1.397 90)
			(size 0.762 0.889)
			(layers "B.Cu" "B.Mask" "B.Paste")
			(net "GND")
		)
		(zone
			(layer "B.Cu")
			(hatch none 0.5)
			(connect_pads
				(clearance 0)
			)
			(min_thickness 0.25)
			(keepout
				(tracks not_allowed)
				(vias allowed)
				(pads allowed)
				(copperpour not_allowed)
				(footprints allowed)
			)
			(placement
				(enabled no)
				(sheetname "")
			)
			(fill
				(thermal_gap 0.5)
				(thermal_bridge_width 0.5)
				(island_removal_mode 0)
			)
			(polygon
				(pts
					(xy 377.5583 -137.4648) (xy 377.5583 -138.2268) (xy 377.0503 -138.2268) (xy 377.0503 -137.4648)
				)
			)
		)
	)
)
